# S9S_MB_2U (Grand Teton) — schematic netlist excerpt (pin names and nets, part order shuffled) for the footprints in the layout excerpt that follows; sources: Cadence DE-HDL packaged netlist, KiCad conversion of 03242023_DA0F0TMBIJ0_F0T_Motherboard_J_brd_V01_OCP.brd

C1096  Q_CAP  0.1UF 6.3V 10% X6S  pkg C0201  page 181 : A = USB3_PCH_TX_DP<4> ; B = USB3_PCH_TX_C_DP<4>
R3891  Q_RES  49.9 1% CHIP  pkg 0402LF  page 98 : A = I3C_SPD_DDRABCD_CPU1_LVC1_SCL_R ; B = I3C_SPD_DDRABCD_CPU1_LVC1_SCL
PC1225  Q_CAP  47UF 4V 20% X6S  pkg C0805  page 262 : A = P1V05_PCH_AUX ; B = GND

(kicad_pcb
	(version 20260206)
	(generator "pcbnew")
	(generator_version "10.0")
	(general
		(thickness 1.6)
		(legacy_teardrops no)
	)
	(paper "A4")
	(title_block
		(title "03242023_DA0F0TMBIJ0_F0T_Motherboard_J_brd_V01_OCP.brd")
		(comment 1 "Grand Teton / footprints 5272-5274 of 6105")
	)
	(layers
		(0 "F.Cu" signal "TOP")
		(4 "In1.Cu" signal "GND")
		(6 "In2.Cu" signal "IN1")
		(8 "In3.Cu" signal "GND1")
		(10 "In4.Cu" signal "IN2")
		(12 "In5.Cu" signal "GND2")
		(14 "In6.Cu" signal "IN3")
		(16 "In7.Cu" signal "GND3")
		(18 "In8.Cu" signal "VCC")
		(20 "In9.Cu" signal "VCC1")
		(22 "In10.Cu" signal "GND4")
		(24 "In11.Cu" signal "IN4")
		(26 "In12.Cu" signal "GND5")
		(28 "In13.Cu" signal "IN5")
		(30 "In14.Cu" signal "GND6")
		(32 "In15.Cu" signal "IN6")
		(34 "In16.Cu" signal "GND7")
		(2 "B.Cu" signal "BOTTOM")
		(9 "F.Adhes" user "F.Adhesive")
		(11 "B.Adhes" user "B.Adhesive")
		(13 "F.Paste" user "Package Geometry/Pastemask Top")
		(15 "B.Paste" user "Package Geometry/Pastemask Bottom")
		(5 "F.SilkS" user "Ref Des/Silkscreen Top")
		(7 "B.SilkS" user "Ref Des/Silkscreen Bottom")
		(1 "F.Mask" user "Board Geometry/Soldermask Top")
		(3 "B.Mask" user "Board Geometry/Soldermask Bottom")
		(17 "Dwgs.User" user "User.Drawings")
		(19 "Cmts.User" user "User.Comments")
		(21 "Eco1.User" user "User.Eco1")
		(23 "Eco2.User" user "User.Eco2")
		(25 "Edge.Cuts" user "Board Geometry/Outline")
		(27 "Margin" user)
		(31 "F.CrtYd" user "Package Geometry/Place Bound Top")
		(29 "B.CrtYd" user "Package Geometry/Place Bound Bottom")
		(35 "F.Fab" user "Ref Des/Assembly Top")
		(33 "B.Fab" user "Ref Des/Assembly Bottom")
	)
	(footprint ""
		(layer "B.Cu")
		(at 53.446426 -316.213744)
		(property "Reference" "R3891"
			(at 0 0 0)
			(layer "B.SilkS")
			(hide yes)
			(effects
				(font
					(size 1.27 1.27)
				)
				(justify mirror)
			)
		)
		(property "Value" ""
			(at 0 0 0)
			(layer "B.Fab")
			(effects
				(font
					(size 1.27 1.27)
				)
				(justify mirror)
			)
		)
		(duplicate_pad_numbers_are_jumpers no)
		(fp_line
			(start -0.7874 -0.4064)
			(end -0.7874 0.4064)
			(stroke
				(width 0.1524)
				(type default)
			)
			(layer "B.SilkS")
		)
		(fp_line
			(start -0.7874 0.4064)
			(end 0.7874 0.4064)
			(stroke
				(width 0.1524)
				(type default)
			)
			(layer "B.SilkS")
		)
		(fp_line
			(start 0.7874 -0.4064)
			(end -0.7874 -0.4064)
			(stroke
				(width 0.1524)
				(type default)
			)
			(layer "B.SilkS")
		)
		(fp_line
			(start 0.7874 0.4064)
			(end 0.7874 -0.4064)
			(stroke
				(width 0.1524)
				(type default)
			)
			(layer "B.SilkS")
		)
		(fp_line
			(start -0.67945 -0.3048)
			(end -0.67945 0.3048)
			(stroke
				(width 0.1)
				(type default)
			)
			(layer "B.Fab")
		)
		(fp_line
			(start -0.67945 0.3048)
			(end -0.120396 0.3048)
			(stroke
				(width 0.1)
				(type default)
			)
			(layer "B.Fab")
		)
		(fp_line
			(start -0.12065 -0.3048)
			(end -0.67945 -0.3048)
			(stroke
				(width 0.1)
				(type default)
			)
			(layer "B.Fab")
		)
		(fp_line
			(start -0.12065 -0.2794)
			(end -0.12065 -0.3048)
			(stroke
				(width 0.1)
				(type default)
			)
			(layer "B.Fab")
		)
		(fp_line
			(start -0.120396 0.2794)
			(end 0.12065 0.2794)
			(stroke
				(width 0.1)
				(type default)
			)
			(layer "B.Fab")
		)
		(fp_line
			(start -0.120396 0.3048)
			(end -0.120396 0.2794)
			(stroke
				(width 0.1)
				(type default)
			)
			(layer "B.Fab")
		)
		(fp_line
			(start 0.12065 -0.305054)
			(end 0.12065 -0.2794)
			(stroke
				(width 0.1)
				(type default)
			)
			(layer "B.Fab")
		)
		(fp_line
			(start 0.12065 -0.2794)
			(end -0.12065 -0.2794)
			(stroke
				(width 0.1)
				(type default)
			)
			(layer "B.Fab")
		)
		(fp_line
			(start 0.12065 0.2794)
			(end 0.12065 0.3048)
			(stroke
				(width 0.1)
				(type default)
			)
			(layer "B.Fab")
		)
		(fp_line
			(start 0.12065 0.3048)
			(end 0.67945 0.3048)
			(stroke
				(width 0.1)
				(type default)
			)
			(layer "B.Fab")
		)
		(fp_line
			(start 0.67945 -0.305054)
			(end 0.12065 -0.305054)
			(stroke
				(width 0.1)
				(type default)
			)
			(layer "B.Fab")
		)
		(fp_line
			(start 0.67945 0.3048)
			(end 0.67945 -0.305054)
			(stroke
				(width 0.1)
				(type default)
			)
			(layer "B.Fab")
		)
		(pad "1" smd circle
			(at 0.40005 0 180)
			(size 0 0)
			(layers "B.Cu" "B.Mask" "B.Paste")
			(net "I3C_SPD_DDRABCD_CPU1_LVC1_SCL_R")
		)
		(pad "2" smd circle
			(at -0.40005 0 180)
			(size 0 0)
			(layers "B.Cu" "B.Mask" "B.Paste")
			(net "I3C_SPD_DDRABCD_CPU1_LVC1_SCL")
		)
	)
	(footprint ""
		(layer "B.Cu")
		(at 125.052836 -24.986742 180)
		(property "Reference" "C1096"
			(at 0 0 0)
			(layer "B.SilkS")
			(hide yes)
			(effects
				(font
					(size 1.27 1.27)
				)
				(justify mirror)
			)
		)
		(property "Value" ""
			(at 0 0 0)
			(layer "B.Fab")
			(effects
				(font
					(size 1.27 1.27)
				)
				(justify mirror)
			)
		)
		(duplicate_pad_numbers_are_jumpers no)
		(fp_line
			(start 0.299974 0.150114)
			(end 0.299974 -0.150114)
			(stroke
				(width 0.1)
				(type default)
			)
			(layer "B.Fab")
		)
		(fp_line
			(start 0.299974 -0.150114)
			(end -0.299974 -0.150114)
			(stroke
				(width 0.1)
				(type default)
			)
			(layer "B.Fab")
		)
		(fp_line
			(start -0.299974 0.150114)
			(end 0.299974 0.150114)
			(stroke
				(width 0.1)
				(type default)
			)
			(layer "B.Fab")
		)
		(fp_line
			(start -0.299974 -0.150114)
			(end -0.299974 0.150114)
			(stroke
				(width 0.1)
				(type default)
			)
			(layer "B.Fab")
		)
		(pad "1" smd rect
			(at 0.2667 0)
			(size 0.3048 0.381)
			(layers "B.Cu" "B.Mask" "B.Paste")
			(net "USB3_PCH_TX_DP<4>")
		)
		(pad "2" smd rect
			(at -0.2667 0)
			(size 0.3048 0.381)
			(layers "B.Cu" "B.Mask" "B.Paste")
			(net "USB3_PCH_TX_C_DP<4>")
		)
	)
	(footprint ""
		(layer "B.Cu")
		(at 272.363946 -71.341996)
		(property "Reference" "PC1225"
			(at 0 0 0)
			(layer "B.SilkS")
			(hide yes)
			(effects
				(font
					(size 1.27 1.27)
				)
				(justify mirror)
			)
		)
		(property "Value" ""
			(at 0 0 0)
			(layer "B.Fab")
			(effects
				(font
					(size 1.27 1.27)
				)
				(justify mirror)
			)
		)
		(duplicate_pad_numbers_are_jumpers no)
		(fp_line
			(start -1.524 -0.762)
			(end -1.524 0.762)
			(stroke
				(width 0.1524)
				(type default)
			)
			(layer "B.SilkS")
		)
		(fp_line
			(start -1.524 0.762)
			(end 1.524 0.762)
			(stroke
				(width 0.1524)
				(type default)
			)
			(layer "B.SilkS")
		)
		(fp_line
			(start 1.524 -0.762)
			(end -1.524 -0.762)
			(stroke
				(width 0.1524)
				(type default)
			)
			(layer "B.SilkS")
		)
		(fp_line
			(start 1.524 0.762)
			(end 1.524 -0.762)
			(stroke
				(width 0.1524)
				(type default)
			)
			(layer "B.SilkS")
		)
		(fp_line
			(start -1.1049 -0.724916)
			(end 1.1049 -0.724916)
			(stroke
				(width 0.1)
				(type default)
			)
			(layer "B.Fab")
		)
		(fp_line
			(start -1.1049 0.724916)
			(end -1.1049 -0.724916)
			(stroke
				(width 0.1)
				(type default)
			)
			(layer "B.Fab")
		)
		(fp_line
			(start 1.1049 -0.724916)
			(end 1.1049 0.724916)
			(stroke
				(width 0.1)
				(type default)
			)
			(layer "B.Fab")
		)
		(fp_line
			(start 1.1049 0.724916)
			(end -1.1049 0.724916)
			(stroke
				(width 0.1)
				(type default)
			)
			(layer "B.Fab")
		)
		(pad "1" smd rect
			(at 0.889 0)
			(size 1.016 1.27)
			(layers "B.Cu" "B.Mask" "B.Paste")
			(net "P1V05_PCH_AUX")
		)
		(pad "2" smd rect
			(at -0.889 0)
			(size 1.016 1.27)
			(layers "B.Cu" "B.Mask" "B.Paste")
			(net "GND")
		)
	)
)
